(kicad_pcb
	(version 20241229)
	(generator "pcbnew")
	(generator_version "9.0")
	(general
		(thickness 1.63)
		(legacy_teardrops no)
	)
	(paper "A4")
	(title_block
		(title "CM4 Baseboard")
		(date "2026-01-05")
		(rev "1.1.1")
		(company "Antmicro Ltd")
		(comment 1 "www.antmicro.com")
		(comment 9 "footprints 282-285 of 506")
	)
	(layers
		(0 "F.Cu" signal)
		(4 "In1.Cu" power)
		(6 "In2.Cu" power)
		(8 "In3.Cu" signal)
		(10 "In4.Cu" signal)
		(2 "B.Cu" signal)
		(9 "F.Adhes" user "F.Adhesive")
		(11 "B.Adhes" user "B.Adhesive")
		(13 "F.Paste" user)
		(15 "B.Paste" user)
		(5 "F.SilkS" user "F.Silkscreen")
		(7 "B.SilkS" user "B.Silkscreen")
		(1 "F.Mask" user)
		(3 "B.Mask" user)
		(17 "Dwgs.User" user "User.Drawings")
		(19 "Cmts.User" user "User.Comments")
		(21 "Eco1.User" user "User.Eco1")
		(23 "Eco2.User" user "User.Eco2")
		(25 "Edge.Cuts" user)
		(27 "Margin" user)
		(31 "F.CrtYd" user "F.Courtyard")
		(29 "B.CrtYd" user "B.Courtyard")
		(35 "F.Fab" user)
		(33 "B.Fab" user)
	)
	(footprint "antmicro-footprints:Spacer_Drill3.7mm_H3mm_9774030151R"
		(layer "F.Cu")
		(at 113.520961 128.314)
		(descr "Spacer M=3 h=3mm fi=5.1mm")
		(property "Reference" "H204"
			(at -0.087999 -3.0375 0)
			(layer "F.SilkS")
			(hide yes)
			(effects
				(font
					(size 0.7 0.7)
					(thickness 0.15)
				)
				(justify left bottom)
			)
		)
		(property "Value" "Spacer_Drill3.7mm_H3mm_9774030151R"
			(at 0 4 0)
			(layer "F.Fab")
			(effects
				(font
					(size 0.7 0.7)
					(thickness 0.15)
				)
				(justify left bottom)
			)
		)
		(property "Datasheet" "https://www.we-online.com/catalog/datasheet/9774030151.pdf"
			(at 0 0 0)
			(layer "F.Fab")
			(hide yes)
			(effects
				(font
					(size 1.27 1.27)
					(thickness 0.15)
				)
			)
		)
		(property "Manufacturer" "Würth Elektronik"
			(at 0 0 0)
			(unlocked yes)
			(layer "F.Fab")
			(hide yes)
			(effects
				(font
					(size 1 1)
					(thickness 0.15)
				)
			)
		)
		(property "MPN" "9774030151R"
			(at 0 0 0)
			(unlocked yes)
			(layer "F.Fab")
			(hide yes)
			(effects
				(font
					(size 1 1)
					(thickness 0.15)
				)
			)
		)
		(property "Author" "Antmicro"
			(at 0 0 0)
			(unlocked yes)
			(layer "F.Fab")
			(hide yes)
			(effects
				(font
					(size 1 1)
					(thickness 0.15)
				)
			)
		)
		(property "License" "Apache-2.0"
			(at 0 0 0)
			(unlocked yes)
			(layer "F.Fab")
			(hide yes)
			(effects
				(font
					(size 1 1)
					(thickness 0.15)
				)
			)
		)
		(sheetname "/Compute module/")
		(sheetfile "compute-module.kicad_sch")
		(solder_paste_margin_ratio -1)
		(attr smd)
		(fp_circle
			(center 0 0)
			(end 3.05 0)
			(stroke
				(width 0.05)
				(type solid)
			)
			(fill no)
			(layer "F.CrtYd")
		)
		(fp_circle
			(center 0 0)
			(end 2.6 0)
			(stroke
				(width 0.15)
				(type solid)
			)
			(fill no)
			(layer "F.Fab")
		)
		(fp_text user "License: Apache-2.0"
			(at -9.6 8.9 0)
			(layer "F.Fab")
			(effects
				(font
					(size 0.7 0.7)
					(thickness 0.15)
				)
				(justify left bottom)
			)
		)
		(fp_text user "Author: Antmicro"
			(at -9.6 7.7 0)
			(layer "F.Fab")
			(effects
				(font
					(size 0.7 0.7)
					(thickness 0.15)
				)
				(justify left bottom)
			)
		)
		(fp_text user "${REFERENCE}"
			(at -9.6 6.5 0)
			(layer "F.Fab")
			(effects
				(font
					(size 0.7 0.7)
					(thickness 0.15)
				)
				(justify left bottom)
			)
		)
		(pad "" smd custom
			(at -1.7 -1.7)
			(size 0.62 0.62)
			(layers "F.Paste")
			(thermal_bridge_angle 90)
			(options
				(clearance outline)
				(anchor circle)
			)
			(primitives
				(gr_arc
					(start -0.250195 1.279127)
					(mid 0.285453 0.294389)
					(end 1.266786 -0.24747)
					(width 0.2)
				)
				(gr_arc
					(start -0.34334 1.279127)
					(mid 0.218448 0.232561)
					(end 1.259603 -0.339191)
					(width 0.2)
				)
				(gr_arc
					(start -0.436309 1.279127)
					(mid 0.152481 0.169693)
					(end 1.255279 -0.431435)
					(width 0.2)
				)
				(gr_arc
					(start -0.529126 1.279127)
					(mid 0.087542 0.105784)
					(end 1.253811 -0.524161)
					(width 0.2)
				)
				(gr_arc
					(start -0.621807 1.279127)
					(mid 0.0309 0.033527)
					(end 1.275473 -0.621136)
					(width 0.2)
				)
				(gr_arc
					(start -0.71437 1.279127)
					(mid -0.037758 -0.026651)
					(end 1.263664 -0.711602)
					(width 0.2)
				)
				(gr_arc
					(start -0.806826 1.279127)
					(mid -0.105837 -0.087395)
					(end 1.253435 -0.802342)
					(width 0.2)
				)
				(gr_arc
					(start -0.899187 1.279127)
					(mid -0.165236 -0.156885)
					(end 1.267475 -0.897258)
					(width 0.2)
				)
				(gr_arc
					(start -0.991463 1.279127)
					(mid -0.228522 -0.222449)
					(end 1.270645 -0.990112)
					(width 0.2)
				)
				(gr_arc
					(start -1.083663 1.279127)
					(mid -0.294507 -0.285313)
					(end 1.266278 -1.081674)
					(width 0.2)
				)
				(gr_line
					(start 1.279127 -0.250195)
					(end 1.279127 -1.083663)
					(width 0.2)
				)
				(gr_line
					(start -0.250195 1.279127)
					(end -1.083663 1.279127)
					(width 0.2)
				)
			)
		)
		(pad "" smd custom
			(at -1.7 1.7 90)
			(size 0.62 0.62)
			(layers "F.Paste")
			(thermal_bridge_angle 90)
			(options
				(clearance outline)
				(anchor circle)
			)
			(primitives
				(gr_arc
					(start -0.250195 1.279127)
					(mid 0.285453 0.294389)
					(end 1.266786 -0.24747)
					(width 0.2)
				)
				(gr_arc
					(start -0.34334 1.279127)
					(mid 0.218448 0.232561)
					(end 1.259603 -0.339191)
					(width 0.2)
				)
				(gr_arc
					(start -0.436309 1.279127)
					(mid 0.152481 0.169693)
					(end 1.255279 -0.431435)
					(width 0.2)
				)
				(gr_arc
					(start -0.529126 1.279127)
					(mid 0.087542 0.105784)
					(end 1.253811 -0.524161)
					(width 0.2)
				)
				(gr_arc
					(start -0.621807 1.279127)
					(mid 0.0309 0.033527)
					(end 1.275473 -0.621136)
					(width 0.2)
				)
				(gr_arc
					(start -0.71437 1.279127)
					(mid -0.037758 -0.026651)
					(end 1.263664 -0.711602)
					(width 0.2)
				)
				(gr_arc
					(start -0.806826 1.279127)
					(mid -0.105837 -0.087395)
					(end 1.253435 -0.802342)
					(width 0.2)
				)
				(gr_arc
					(start -0.899187 1.279127)
					(mid -0.165236 -0.156885)
					(end 1.267475 -0.897258)
					(width 0.2)
				)
				(gr_arc
					(start -0.991463 1.279127)
					(mid -0.228522 -0.222449)
					(end 1.270645 -0.990112)
					(width 0.2)
				)
				(gr_arc
					(start -1.083663 1.279127)
					(mid -0.294507 -0.285313)
					(end 1.266278 -1.081674)
					(width 0.2)
				)
				(gr_line
					(start 1.279127 -0.250195)
					(end 1.279127 -1.083663)
					(width 0.2)
				)
				(gr_line
					(start -0.250195 1.279127)
					(end -1.083663 1.279127)
					(width 0.2)
				)
			)
		)
		(pad "" smd custom
			(at 1.7 -1.7 270)
			(size 0.62 0.62)
			(layers "F.Paste")
			(thermal_bridge_angle 90)
			(options
				(clearance outline)
				(anchor circle)
			)
			(primitives
				(gr_arc
					(start -0.250195 1.279127)
					(mid 0.285453 0.294389)
					(end 1.266786 -0.24747)
					(width 0.2)
				)
				(gr_arc
					(start -0.34334 1.279127)
					(mid 0.218448 0.232561)
					(end 1.259603 -0.339191)
					(width 0.2)
				)
				(gr_arc
					(start -0.436309 1.279127)
					(mid 0.152481 0.169693)
					(end 1.255279 -0.431435)
					(width 0.2)
				)
				(gr_arc
					(start -0.529126 1.279127)
					(mid 0.087542 0.105784)
					(end 1.253811 -0.524161)
					(width 0.2)
				)
				(gr_arc
					(start -0.621807 1.279127)
					(mid 0.0309 0.033527)
					(end 1.275473 -0.621136)
					(width 0.2)
				)
				(gr_arc
					(start -0.71437 1.279127)
					(mid -0.037758 -0.026651)
					(end 1.263664 -0.711602)
					(width 0.2)
				)
				(gr_arc
					(start -0.806826 1.279127)
					(mid -0.105837 -0.087395)
					(end 1.253435 -0.802342)
					(width 0.2)
				)
				(gr_arc
					(start -0.899187 1.279127)
					(mid -0.165236 -0.156885)
					(end 1.267475 -0.897258)
					(width 0.2)
				)
				(gr_arc
					(start -0.991463 1.279127)
					(mid -0.228522 -0.222449)
					(end 1.270645 -0.990112)
					(width 0.2)
				)
				(gr_arc
					(start -1.083663 1.279127)
					(mid -0.294507 -0.285313)
					(end 1.266278 -1.081674)
					(width 0.2)
				)
				(gr_line
					(start 1.279127 -0.250195)
					(end 1.279127 -1.083663)
					(width 0.2)
				)
				(gr_line
					(start -0.250195 1.279127)
					(end -1.083663 1.279127)
					(width 0.2)
				)
			)
		)
		(pad "" smd custom
			(at 1.7 1.7 180)
			(size 0.62 0.62)
			(layers "F.Paste")
			(thermal_bridge_angle 90)
			(options
				(clearance outline)
				(anchor circle)
			)
			(primitives
				(gr_arc
					(start -0.250195 1.279127)
					(mid 0.285453 0.294389)
					(end 1.266786 -0.24747)
					(width 0.2)
				)
				(gr_arc
					(start -0.34334 1.279127)
					(mid 0.218448 0.232561)
					(end 1.259603 -0.339191)
					(width 0.2)
				)
				(gr_arc
					(start -0.436309 1.279127)
					(mid 0.152481 0.169693)
					(end 1.255279 -0.431435)
					(width 0.2)
				)
				(gr_arc
					(start -0.529126 1.279127)
					(mid 0.087542 0.105784)
					(end 1.253811 -0.524161)
					(width 0.2)
				)
				(gr_arc
					(start -0.621807 1.279127)
					(mid 0.0309 0.033527)
					(end 1.275473 -0.621136)
					(width 0.2)
				)
				(gr_arc
					(start -0.71437 1.279127)
					(mid -0.037758 -0.026651)
					(end 1.263664 -0.711602)
					(width 0.2)
				)
				(gr_arc
					(start -0.806826 1.279127)
					(mid -0.105837 -0.087395)
					(end 1.253435 -0.802342)
					(width 0.2)
				)
				(gr_arc
					(start -0.899187 1.279127)
					(mid -0.165236 -0.156885)
					(end 1.267475 -0.897258)
					(width 0.2)
				)
				(gr_arc
					(start -0.991463 1.279127)
					(mid -0.228522 -0.222449)
					(end 1.270645 -0.990112)
					(width 0.2)
				)
				(gr_arc
					(start -1.083663 1.279127)
					(mid -0.294507 -0.285313)
					(end 1.266278 -1.081674)
					(width 0.2)
				)
				(gr_line
					(start 1.279127 -0.250195)
					(end 1.279127 -1.083663)
					(width 0.2)
				)
				(gr_line
					(start -0.250195 1.279127)
					(end -1.083663 1.279127)
					(width 0.2)
				)
			)
		)
		(pad "1" thru_hole circle
			(at 0 0)
			(size 6 6)
			(drill 3.7)
			(layers "*.Cu" "*.Mask")
			(remove_unused_layers no)
			(net 3 "GND")
			(pintype "passive")
		)
	)
	(footprint "antmicro-footprints:R_0402_1005Metric"
		(layer "F.Cu")
		(at 81.837962 124.4715)
		(descr "Resistor SMD 0402")
		(tags "resistor SMD 0402")
		(property "Reference" "R918"
			(at 0.045 1.265 0)
			(layer "F.SilkS")
			(effects
				(font
					(size 0.7 0.7)
					(thickness 0.15)
				)
				(justify left bottom)
			)
		)
		(property "Value" "R_470R_0402"
			(at -1.011843 1.772047 0)
			(layer "F.Fab")
			(effects
				(font
					(size 0.7 0.7)
					(thickness 0.15)
				)
				(justify left bottom)
			)
		)
		(property "Datasheet" "https://www.bourns.com/docs/product-datasheets/cr.pdf"
			(at 0 0 0)
			(layer "F.Fab")
			(hide yes)
			(effects
				(font
					(size 1.27 1.27)
					(thickness 0.15)
				)
			)
		)
		(property "Manufacturer" "Bourns"
			(at 0 0 0)
			(unlocked yes)
			(layer "F.Fab")
			(hide yes)
			(effects
				(font
					(size 1 1)
					(thickness 0.15)
				)
			)
		)
		(property "MPN" "CR0402-FX-4700GLF"
			(at 0 0 0)
			(unlocked yes)
			(layer "F.Fab")
			(hide yes)
			(effects
				(font
					(size 1 1)
					(thickness 0.15)
				)
			)
		)
		(property "Val" "470R"
			(at 0 0 0)
			(unlocked yes)
			(layer "F.Fab")
			(hide yes)
			(effects
				(font
					(size 1 1)
					(thickness 0.15)
				)
			)
		)
		(property "License" "Apache-2.0"
			(at 0 0 0)
			(unlocked yes)
			(layer "F.Fab")
			(hide yes)
			(effects
				(font
					(size 1 1)
					(thickness 0.15)
				)
			)
		)
		(property "Author" "Antmicro"
			(at 0 0 0)
			(unlocked yes)
			(layer "F.Fab")
			(hide yes)
			(effects
				(font
					(size 1 1)
					(thickness 0.15)
				)
			)
		)
		(property "Tolerance" "1%"
			(at 0 0 0)
			(unlocked yes)
			(layer "F.Fab")
			(hide yes)
			(effects
				(font
					(size 1 1)
					(thickness 0.15)
				)
			)
		)
		(sheetname "/USB/")
		(sheetfile "usb.kicad_sch")
		(attr smd)
		(fp_rect
			(start -0.925 -0.47)
			(end 0.925 0.47)
			(stroke
				(width 0.05)
				(type default)
			)
			(fill no)
			(layer "F.CrtYd")
		)
		(fp_rect
			(start -0.5 -0.25)
			(end 0.5 0.25)
			(stroke
				(width 0.15)
				(type solid)
			)
			(fill no)
			(layer "F.Fab")
		)
		(fp_text user "Author: Antmicro"
			(at -0.95 4.169 0)
			(layer "F.Fab")
			(effects
				(font
					(size 0.7 0.7)
					(thickness 0.15)
				)
				(justify left bottom)
			)
		)
		(fp_text user "${REFERENCE}"
			(at -0.95 3.168 0)
			(layer "F.Fab")
			(effects
				(font
					(size 0.7 0.7)
					(thickness 0.15)
				)
				(justify left bottom)
			)
		)
		(fp_text user "License: Apache-2.0"
			(at -0.95 5.169 0)
			(layer "F.Fab")
			(effects
				(font
					(size 0.7 0.7)
					(thickness 0.15)
				)
				(justify left bottom)
			)
		)
		(pad "1" smd roundrect
			(at -0.48 0)
			(size 0.59 0.64)
			(layers "F.Cu" "F.Mask" "F.Paste")
			(roundrect_rratio 0.25)
			(net 484 "Net-(D907-A)")
			(pintype "passive")
		)
		(pad "2" smd roundrect
			(at 0.48 0)
			(size 0.59 0.64)
			(layers "F.Cu" "F.Mask" "F.Paste")
			(roundrect_rratio 0.25)
			(net 113 "/USB/OUT_FTDI")
			(pintype "passive")
		)
	)
	(footprint "antmicro-footprints:C_0402_1005Metric"
		(layer "F.Cu")
		(at 63.617962 179.1505)
		(descr "Capacitor SMD 0402")
		(tags "capacitor SMD 0402")
		(property "Reference" "C820"
			(at -16.17 -0.624 0)
			(layer "F.SilkS")
			(effects
				(font
					(size 0.7 0.7)
					(thickness 0.15)
				)
				(justify left bottom)
			)
		)
		(property "Value" "C_template_name_0402"
			(at -1.022927 2.155213 0)
			(layer "F.Fab")
			(effects
				(font
					(size 0.7 0.7)
					(thickness 0.15)
				)
				(justify left bottom)
			)
		)
		(property "Datasheet" "template_datasheet"
			(at 0 0 0)
			(layer "F.Fab")
			(hide yes)
			(effects
				(font
					(size 1.27 1.27)
					(thickness 0.15)
				)
			)
		)
		(property "MPN" "template_MPN"
			(at 0 0 0)
			(unlocked yes)
			(layer "F.Fab")
			(hide yes)
			(effects
				(font
					(size 1 1)
					(thickness 0.15)
				)
			)
		)
		(property "Manufacturer" "template_manufacturer"
			(at 0 0 0)
			(unlocked yes)
			(layer "F.Fab")
			(hide yes)
			(effects
				(font
					(size 1 1)
					(thickness 0.15)
				)
			)
		)
		(property "License" "Apache-2.0"
			(at 0 0 0)
			(unlocked yes)
			(layer "F.Fab")
			(hide yes)
			(effects
				(font
					(size 1 1)
					(thickness 0.15)
				)
			)
		)
		(property "Author" "Antmicro"
			(at 0 0 0)
			(unlocked yes)
			(layer "F.Fab")
			(hide yes)
			(effects
				(font
					(size 1 1)
					(thickness 0.15)
				)
			)
		)
		(property "Val" "template_value"
			(at 0 0 0)
			(unlocked yes)
			(layer "F.Fab")
			(hide yes)
			(effects
				(font
					(size 1 1)
					(thickness 0.15)
				)
			)
		)
		(property "Voltage" "template_voltage"
			(at 0 0 0)
			(unlocked yes)
			(layer "F.Fab")
			(hide yes)
			(effects
				(font
					(size 1 1)
					(thickness 0.15)
				)
			)
		)
		(property "Dielectric" "template_dielectric"
			(at 0 0 0)
			(unlocked yes)
			(layer "F.Fab")
			(hide yes)
			(effects
				(font
					(size 1 1)
					(thickness 0.15)
				)
			)
		)
		(sheetname "/Peripherals/")
		(sheetfile "peripherals.kicad_sch")
		(attr smd exclude_from_pos_files exclude_from_bom dnp)
		(fp_rect
			(start -0.925 -0.47)
			(end 0.925 0.47)
			(stroke
				(width 0.05)
				(type default)
			)
			(fill no)
			(layer "F.CrtYd")
		)
		(fp_line
			(start -0.494 -0.25)
			(end 0.504 -0.25)
			(stroke
				(width 0.15)
				(type solid)
			)
			(layer "F.Fab")
		)
		(fp_line
			(start -0.494 0.248)
			(end -0.494 -0.25)
			(stroke
				(width 0.15)
				(type solid)
			)
			(layer "F.Fab")
		)
		(fp_line
			(start 0.504 -0.25)
			(end 0.504 0.248)
			(stroke
				(width 0.15)
				(type solid)
			)
			(layer "F.Fab")
		)
		(fp_line
			(start 0.504 0.248)
			(end -0.494 0.248)
			(stroke
				(width 0.15)
				(type solid)
			)
			(layer "F.Fab")
		)
		(fp_text user "License: Apache-2.0"
			(at -0.939 5.799 0)
			(layer "F.Fab")
			(effects
				(font
					(size 0.7 0.7)
					(thickness 0.15)
				)
				(justify left bottom)
			)
		)
		(fp_text user "${REFERENCE}"
			(at -0.939 4.599 0)
			(layer "F.Fab")
			(effects
				(font
					(size 0.7 0.7)
					(thickness 0.15)
				)
				(justify left bottom)
			)
		)
		(fp_text user "Author: Antmicro"
			(at -0.939 3.399 0)
			(layer "F.Fab")
			(effects
				(font
					(size 0.7 0.7)
					(thickness 0.15)
				)
				(justify left bottom)
			)
		)
		(pad "1" smd roundrect
			(at -0.48 0)
			(size 0.59 0.64)
			(layers "F.Cu" "F.Mask" "F.Paste")
			(roundrect_rratio 0.25)
			(net 100 "Net-(C811-Pad2)")
			(pintype "passive")
		)
		(pad "2" smd roundrect
			(at 0.48 0)
			(size 0.59 0.64)
			(layers "F.Cu" "F.Mask" "F.Paste")
			(roundrect_rratio 0.25)
			(net 109 "Net-(C816-Pad2)")
			(pintype "passive")
		)
	)
	(footprint "antmicro-footprints:C_0402_1005Metric"
		(layer "F.Cu")
		(at 61.442962 174.2665 180)
		(descr "Capacitor SMD 0402")
		(tags "capacitor SMD 0402")
		(property "Reference" "C814"
			(at 13.942962 3.0165 0)
			(layer "F.SilkS")
			(effects
				(font
					(size 0.7 0.7)
					(thickness 0.15)
				)
				(justify right top)
			)
		)
		(property "Value" "C_12p_0402"
			(at -1.022927 2.155213 0)
			(layer "F.Fab")
			(effects
				(font
					(size 0.7 0.7)
					(thickness 0.15)
				)
				(justify right top)
			)
		)
		(property "Datasheet" "https://product.tdk.com/en/search/capacitor/ceramic/mlcc/info?part_no=CGA2B2C0G1H120J050BA"
			(at 0 0 0)
			(layer "F.Fab")
			(hide yes)
			(effects
				(font
					(size 1.27 1.27)
					(thickness 0.15)
				)
			)
		)
		(property "Description" "SMD Multilayer Ceramic Capacitor, 12 pF, 50 V, 0402 [1005 Metric], ± 5%, C0G / NP0, CGA"
			(at 0 0 0)
			(layer "F.Fab")
			(hide yes)
			(effects
				(font
					(size 1.27 1.27)
					(thickness 0.15)
				)
			)
		)
		(property "MPN" "CGA2B2C0G1H120J050BA"
			(at 0 0 180)
			(unlocked yes)
			(layer "F.Fab")
			(hide yes)
			(effects
				(font
					(size 1 1)
					(thickness 0.15)
				)
			)
		)
		(property "Manufacturer" "TDK"
			(at 0 0 180)
			(unlocked yes)
			(layer "F.Fab")
			(hide yes)
			(effects
				(font
					(size 1 1)
					(thickness 0.15)
				)
			)
		)
		(property "License" "Apache-2.0"
			(at 0 0 180)
			(unlocked yes)
			(layer "F.Fab")
			(hide yes)
			(effects
				(font
					(size 1 1)
					(thickness 0.15)
				)
			)
		)
		(property "Author" "Antmicro"
			(at 0 0 180)
			(unlocked yes)
			(layer "F.Fab")
			(hide yes)
			(effects
				(font
					(size 1 1)
					(thickness 0.15)
				)
			)
		)
		(property "Val" "12p"
			(at 0 0 180)
			(unlocked yes)
			(layer "F.Fab")
			(hide yes)
			(effects
				(font
					(size 1 1)
					(thickness 0.15)
				)
			)
		)
		(property "Voltage" ""
			(at 0 0 180)
			(unlocked yes)
			(layer "F.Fab")
			(hide yes)
			(effects
				(font
					(size 1 1)
					(thickness 0.15)
				)
			)
		)
		(property "Dielectric" ""
			(at 0 0 180)
			(unlocked yes)
			(layer "F.Fab")
			(hide yes)
			(effects
				(font
					(size 1 1)
					(thickness 0.15)
				)
			)
		)
		(sheetname "/Peripherals/")
		(sheetfile "peripherals.kicad_sch")
		(attr smd)
		(fp_rect
			(start -0.925 -0.47)
			(end 0.925 0.47)
			(stroke
				(width 0.05)
				(type default)
			)
			(fill no)
			(layer "F.CrtYd")
		)
		(fp_line
			(start 0.504 0.248)
			(end -0.494 0.248)
			(stroke
				(width 0.15)
				(type solid)
			)
			(layer "F.Fab")
		)
		(fp_line
			(start 0.504 -0.25)
			(end 0.504 0.248)
			(stroke
				(width 0.15)
				(type solid)
			)
			(layer "F.Fab")
		)
		(fp_line
			(start -0.494 0.248)
			(end -0.494 -0.25)
			(stroke
				(width 0.15)
				(type solid)
			)
			(layer "F.Fab")
		)
		(fp_line
			(start -0.494 -0.25)
			(end 0.504 -0.25)
			(stroke
				(width 0.15)
				(type solid)
			)
			(layer "F.Fab")
		)
		(fp_text user "License: Apache-2.0"
			(at -0.939 5.799 0)
			(layer "F.Fab")
			(effects
				(font
					(size 0.7 0.7)
					(thickness 0.15)
				)
				(justify right top)
			)
		)
		(fp_text user "Author: Antmicro"
			(at -0.939 3.399 0)
			(layer "F.Fab")
			(effects
				(font
					(size 0.7 0.7)
					(thickness 0.15)
				)
				(justify right top)
			)
		)
		(fp_text user "${REFERENCE}"
			(at -0.939 4.599 0)
			(layer "F.Fab")
			(effects
				(font
					(size 0.7 0.7)
					(thickness 0.15)
				)
				(justify right top)
			)
		)
		(pad "1" smd roundrect
			(at -0.48 0 180)
			(size 0.59 0.64)
			(layers "F.Cu" "F.Mask" "F.Paste")
			(roundrect_rratio 0.25)
			(net 107 "Net-(U801-ANT2)")
			(pintype "passive")
		)
		(pad "2" smd roundrect
			(at 0.48 0 180)
			(size 0.59 0.64)
			(layers "F.Cu" "F.Mask" "F.Paste")
			(roundrect_rratio 0.25)
			(net 106 "Net-(C814-Pad2)")
			(pintype "passive")
		)
	)
)
